# S9S_MB_2U (Grand Teton) — schematic netlist excerpt (pin names and nets, part order shuffled) for the footprints in the layout excerpt that follows; sources: Cadence DE-HDL packaged netlist, KiCad conversion of 03242023_DA0F0TMBIJ0_F0T_Motherboard_J_brd_V01_OCP.brd

PR3987  Q_RES  2K 0.1% CHIP  pkg 0402LF  page 303 : A = HSC_CS_4 ; B = AGND_HSC
R3568  Q_RES  33.2 1% CHIP  pkg 0402LF  page 172 : A = SMB_INA230_3_3V3AUX_SCL_R ; B = SMB_INA230_3_3V3AUX_SCL_R1
PC2163  Q_CAP  10UF 16V 10% EMPTY  pkg C0805  page 157 : A = P3V3_OCP_SFF_R ; B = GND

(kicad_pcb
	(version 20260206)
	(generator "pcbnew")
	(generator_version "10.0")
	(general
		(thickness 1.6)
		(legacy_teardrops no)
	)
	(paper "A4")
	(title_block
		(title "03242023_DA0F0TMBIJ0_F0T_Motherboard_J_brd_V01_OCP.brd")
		(comment 1 "Grand Teton / footprints 1566-1568 of 6105")
	)
	(layers
		(0 "F.Cu" signal "TOP")
		(4 "In1.Cu" signal "GND")
		(6 "In2.Cu" signal "IN1")
		(8 "In3.Cu" signal "GND1")
		(10 "In4.Cu" signal "IN2")
		(12 "In5.Cu" signal "GND2")
		(14 "In6.Cu" signal "IN3")
		(16 "In7.Cu" signal "GND3")
		(18 "In8.Cu" signal "VCC")
		(20 "In9.Cu" signal "VCC1")
		(22 "In10.Cu" signal "GND4")
		(24 "In11.Cu" signal "IN4")
		(26 "In12.Cu" signal "GND5")
		(28 "In13.Cu" signal "IN5")
		(30 "In14.Cu" signal "GND6")
		(32 "In15.Cu" signal "IN6")
		(34 "In16.Cu" signal "GND7")
		(2 "B.Cu" signal "BOTTOM")
		(9 "F.Adhes" user "F.Adhesive")
		(11 "B.Adhes" user "B.Adhesive")
		(13 "F.Paste" user "Package Geometry/Pastemask Top")
		(15 "B.Paste" user "Package Geometry/Pastemask Bottom")
		(5 "F.SilkS" user "Ref Des/Silkscreen Top")
		(7 "B.SilkS" user "Ref Des/Silkscreen Bottom")
		(1 "F.Mask" user "Board Geometry/Soldermask Top")
		(3 "B.Mask" user "Board Geometry/Soldermask Bottom")
		(17 "Dwgs.User" user "User.Drawings")
		(19 "Cmts.User" user "User.Comments")
		(21 "Eco1.User" user "User.Eco1")
		(23 "Eco2.User" user "User.Eco2")
		(25 "Edge.Cuts" user "Board Geometry/Outline")
		(27 "Margin" user)
		(31 "F.CrtYd" user "Package Geometry/Place Bound Top")
		(29 "B.CrtYd" user "Package Geometry/Place Bound Bottom")
		(35 "F.Fab" user "Ref Des/Assembly Top")
		(33 "B.Fab" user "Ref Des/Assembly Bottom")
	)
	(footprint ""
		(layer "F.Cu")
		(at 72.4662 -34.788348 180)
		(property "Reference" "R3568"
			(at 0 0 180)
			(layer "F.SilkS")
			(hide yes)
			(effects
				(font
					(size 1.27 1.27)
				)
			)
		)
		(property "Value" ""
			(at 0 0 180)
			(layer "F.Fab")
			(effects
				(font
					(size 1.27 1.27)
				)
			)
		)
		(duplicate_pad_numbers_are_jumpers no)
		(fp_line
			(start 0.7874 0.4064)
			(end -0.7874 0.4064)
			(stroke
				(width 0.1524)
				(type default)
			)
			(layer "F.SilkS")
		)
		(fp_line
			(start 0.7874 -0.4064)
			(end 0.7874 0.4064)
			(stroke
				(width 0.1524)
				(type default)
			)
			(layer "F.SilkS")
		)
		(fp_line
			(start -0.7874 0.4064)
			(end -0.7874 -0.4064)
			(stroke
				(width 0.1524)
				(type default)
			)
			(layer "F.SilkS")
		)
		(fp_line
			(start -0.7874 -0.4064)
			(end 0.7874 -0.4064)
			(stroke
				(width 0.1524)
				(type default)
			)
			(layer "F.SilkS")
		)
		(fp_line
			(start 0.67945 0.3048)
			(end 0.120396 0.3048)
			(stroke
				(width 0.1)
				(type default)
			)
			(layer "F.Fab")
		)
		(fp_line
			(start 0.67945 -0.3048)
			(end 0.67945 0.3048)
			(stroke
				(width 0.1)
				(type default)
			)
			(layer "F.Fab")
		)
		(fp_line
			(start 0.12065 -0.2794)
			(end 0.12065 -0.3048)
			(stroke
				(width 0.1)
				(type default)
			)
			(layer "F.Fab")
		)
		(fp_line
			(start 0.12065 -0.3048)
			(end 0.67945 -0.3048)
			(stroke
				(width 0.1)
				(type default)
			)
			(layer "F.Fab")
		)
		(fp_line
			(start 0.120396 0.3048)
			(end 0.120396 0.2794)
			(stroke
				(width 0.1)
				(type default)
			)
			(layer "F.Fab")
		)
		(fp_line
			(start 0.120396 0.2794)
			(end -0.12065 0.2794)
			(stroke
				(width 0.1)
				(type default)
			)
			(layer "F.Fab")
		)
		(fp_line
			(start -0.12065 0.3048)
			(end -0.67945 0.3048)
			(stroke
				(width 0.1)
				(type default)
			)
			(layer "F.Fab")
		)
		(fp_line
			(start -0.12065 0.2794)
			(end -0.12065 0.3048)
			(stroke
				(width 0.1)
				(type default)
			)
			(layer "F.Fab")
		)
		(fp_line
			(start -0.12065 -0.2794)
			(end 0.12065 -0.2794)
			(stroke
				(width 0.1)
				(type default)
			)
			(layer "F.Fab")
		)
		(fp_line
			(start -0.12065 -0.305054)
			(end -0.12065 -0.2794)
			(stroke
				(width 0.1)
				(type default)
			)
			(layer "F.Fab")
		)
		(fp_line
			(start -0.67945 0.3048)
			(end -0.67945 -0.305054)
			(stroke
				(width 0.1)
				(type default)
			)
			(layer "F.Fab")
		)
		(fp_line
			(start -0.67945 -0.305054)
			(end -0.12065 -0.305054)
			(stroke
				(width 0.1)
				(type default)
			)
			(layer "F.Fab")
		)
		(pad "1" smd circle
			(at -0.40005 0 180)
			(size 0 0)
			(layers "F.Cu" "F.Mask" "F.Paste")
			(net "SMB_INA230_3_3V3AUX_SCL_R")
		)
		(pad "2" smd circle
			(at 0.40005 0 180)
			(size 0 0)
			(layers "F.Cu" "F.Mask" "F.Paste")
			(net "SMB_INA230_3_3V3AUX_SCL_R1")
		)
	)
	(footprint ""
		(layer "F.Cu")
		(at 226.733608 -401.775422 180)
		(property "Reference" "PR3987"
			(at 0 0 180)
			(layer "F.SilkS")
			(hide yes)
			(effects
				(font
					(size 1.27 1.27)
				)
			)
		)
		(property "Value" ""
			(at 0 0 180)
			(layer "F.Fab")
			(effects
				(font
					(size 1.27 1.27)
				)
			)
		)
		(duplicate_pad_numbers_are_jumpers no)
		(fp_line
			(start 0.7874 0.4064)
			(end -0.7874 0.4064)
			(stroke
				(width 0.1524)
				(type default)
			)
			(layer "F.SilkS")
		)
		(fp_line
			(start 0.7874 -0.4064)
			(end 0.7874 0.4064)
			(stroke
				(width 0.1524)
				(type default)
			)
			(layer "F.SilkS")
		)
		(fp_line
			(start -0.7874 0.4064)
			(end -0.7874 -0.4064)
			(stroke
				(width 0.1524)
				(type default)
			)
			(layer "F.SilkS")
		)
		(fp_line
			(start -0.7874 -0.4064)
			(end 0.7874 -0.4064)
			(stroke
				(width 0.1524)
				(type default)
			)
			(layer "F.SilkS")
		)
		(fp_line
			(start 0.67945 0.3048)
			(end 0.120396 0.3048)
			(stroke
				(width 0.1)
				(type default)
			)
			(layer "F.Fab")
		)
		(fp_line
			(start 0.67945 -0.3048)
			(end 0.67945 0.3048)
			(stroke
				(width 0.1)
				(type default)
			)
			(layer "F.Fab")
		)
		(fp_line
			(start 0.12065 -0.2794)
			(end 0.12065 -0.3048)
			(stroke
				(width 0.1)
				(type default)
			)
			(layer "F.Fab")
		)
		(fp_line
			(start 0.12065 -0.3048)
			(end 0.67945 -0.3048)
			(stroke
				(width 0.1)
				(type default)
			)
			(layer "F.Fab")
		)
		(fp_line
			(start 0.120396 0.3048)
			(end 0.120396 0.2794)
			(stroke
				(width 0.1)
				(type default)
			)
			(layer "F.Fab")
		)
		(fp_line
			(start 0.120396 0.2794)
			(end -0.12065 0.2794)
			(stroke
				(width 0.1)
				(type default)
			)
			(layer "F.Fab")
		)
		(fp_line
			(start -0.12065 0.3048)
			(end -0.67945 0.3048)
			(stroke
				(width 0.1)
				(type default)
			)
			(layer "F.Fab")
		)
		(fp_line
			(start -0.12065 0.2794)
			(end -0.12065 0.3048)
			(stroke
				(width 0.1)
				(type default)
			)
			(layer "F.Fab")
		)
		(fp_line
			(start -0.12065 -0.2794)
			(end 0.12065 -0.2794)
			(stroke
				(width 0.1)
				(type default)
			)
			(layer "F.Fab")
		)
		(fp_line
			(start -0.12065 -0.305054)
			(end -0.12065 -0.2794)
			(stroke
				(width 0.1)
				(type default)
			)
			(layer "F.Fab")
		)
		(fp_line
			(start -0.67945 0.3048)
			(end -0.67945 -0.305054)
			(stroke
				(width 0.1)
				(type default)
			)
			(layer "F.Fab")
		)
		(fp_line
			(start -0.67945 -0.305054)
			(end -0.12065 -0.305054)
			(stroke
				(width 0.1)
				(type default)
			)
			(layer "F.Fab")
		)
		(pad "1" smd circle
			(at -0.40005 0 180)
			(size 0 0)
			(layers "F.Cu" "F.Mask" "F.Paste")
			(net "HSC_CS_4")
		)
		(pad "2" smd circle
			(at 0.40005 0 180)
			(size 0 0)
			(layers "F.Cu" "F.Mask" "F.Paste")
			(net "AGND_HSC")
		)
	)
	(footprint ""
		(layer "F.Cu")
		(at 423.56278 -106.129328 90)
		(property "Reference" "PC2163"
			(at 0 0 90)
			(layer "F.SilkS")
			(hide yes)
			(effects
				(font
					(size 1.27 1.27)
				)
			)
		)
		(property "Value" ""
			(at 0 0 90)
			(layer "F.Fab")
			(effects
				(font
					(size 1.27 1.27)
				)
			)
		)
		(duplicate_pad_numbers_are_jumpers no)
		(fp_line
			(start 1.524 -0.762)
			(end 1.524 0.762)
			(stroke
				(width 0.1524)
				(type default)
			)
			(layer "F.SilkS")
		)
		(fp_line
			(start -1.524 -0.762)
			(end 1.524 -0.762)
			(stroke
				(width 0.1524)
				(type default)
			)
			(layer "F.SilkS")
		)
		(fp_line
			(start 1.524 0.762)
			(end -1.524 0.762)
			(stroke
				(width 0.1524)
				(type default)
			)
			(layer "F.SilkS")
		)
		(fp_line
			(start -1.524 0.762)
			(end -1.524 -0.762)
			(stroke
				(width 0.1524)
				(type default)
			)
			(layer "F.SilkS")
		)
		(fp_line
			(start 1.1049 -0.724916)
			(end -1.1049 -0.724916)
			(stroke
				(width 0.1)
				(type default)
			)
			(layer "F.Fab")
		)
		(fp_line
			(start -1.1049 -0.724916)
			(end -1.1049 0.724916)
			(stroke
				(width 0.1)
				(type default)
			)
			(layer "F.Fab")
		)
		(fp_line
			(start 1.1049 0.724916)
			(end 1.1049 -0.724916)
			(stroke
				(width 0.1)
				(type default)
			)
			(layer "F.Fab")
		)
		(fp_line
			(start -1.1049 0.724916)
			(end 1.1049 0.724916)
			(stroke
				(width 0.1)
				(type default)
			)
			(layer "F.Fab")
		)
		(pad "1" smd rect
			(at -0.889 0 270)
			(size 1.016 1.27)
			(layers "F.Cu" "F.Mask" "F.Paste")
			(net "P3V3_OCP_SFF_R")
		)
		(pad "2" smd rect
			(at 0.889 0 270)
			(size 1.016 1.27)
			(layers "F.Cu" "F.Mask" "F.Paste")
			(net "GND")
		)
	)
)
